(kicad_pcb
	(version 20260206)
	(generator "pcbnew")
	(generator_version "10.0")
	(general
		(thickness 1.6)
		(legacy_teardrops no)
	)
	(paper "A4")
	(title_block
		(title "01162023_DA0F0TEBIF0_F0T_Expander_BD_F_brd_V02_OCP.brd")
		(comment 1 "Grand Teton / footprint 6602 of 9728 (PEX1), pads 2359-2397 of 2397")
	)
	(layers
		(0 "F.Cu" signal "TOP")
		(4 "In1.Cu" signal "GND")
		(6 "In2.Cu" signal "VCC")
		(8 "In3.Cu" signal "VCC1")
		(10 "In4.Cu" signal "GND1")
		(12 "In5.Cu" signal "IN1")
		(14 "In6.Cu" signal "GND2")
		(16 "In7.Cu" signal "IN2")
		(18 "In8.Cu" signal "GND3")
		(20 "In9.Cu" signal "IN3")
		(22 "In10.Cu" signal "GND4")
		(24 "In11.Cu" signal "IN4")
		(26 "In12.Cu" signal "GND5")
		(28 "In13.Cu" signal "IN5")
		(30 "In14.Cu" signal "GND6")
		(32 "In15.Cu" signal "IN6")
		(34 "In16.Cu" signal "GND7")
		(2 "B.Cu" signal "BOTTOM")
		(9 "F.Adhes" user "F.Adhesive")
		(11 "B.Adhes" user "B.Adhesive")
		(13 "F.Paste" user "Package Geometry/Pastemask Top")
		(15 "B.Paste" user "Package Geometry/Pastemask Bottom")
		(5 "F.SilkS" user "Ref Des/Silkscreen Top")
		(7 "B.SilkS" user "Ref Des/Silkscreen Bottom")
		(1 "F.Mask" user "Board Geometry/Soldermask Top")
		(3 "B.Mask" user "Board Geometry/Soldermask Bottom")
		(17 "Dwgs.User" user "User.Drawings")
		(19 "Cmts.User" user "User.Comments")
		(21 "Eco1.User" user "User.Eco1")
		(23 "Eco2.User" user "User.Eco2")
		(25 "Edge.Cuts" user "Board Geometry/Outline")
		(27 "Margin" user)
		(31 "F.CrtYd" user "Package Geometry/Place Bound Top")
		(29 "B.CrtYd" user "Package Geometry/Place Bound Bottom")
		(35 "F.Fab" user "Ref Des/Assembly Top")
		(33 "B.Fab" user "Ref Des/Assembly Bottom")
	)
	(footprint ""
		(layer "F.Cu")
		(at 175.749966 -295.89984)
		(property "Reference" "PEX1"
			(at -3.353562 35.593274 0)
			(unlocked yes)
			(layer "F.SilkS")
			(effects
				(font
					(size 2.032 1.524)
					(thickness 0.1524)
				)
				(justify left)
			)
		)
		(property "Value" ""
			(at 0 0 0)
			(layer "F.Fab")
			(effects
				(font
					(size 1.27 1.27)
				)
			)
		)
		(duplicate_pad_numbers_are_jumpers no)
		(pad "Y11" smd circle
			(at -13.299948 -4.750054)
			(size 0.4572 0.4572)
			(layers "F.Cu" "F.Mask" "F.Paste")
			(net "GND")
		)
		(pad "Y12" smd circle
			(at -12.349988 -4.750054)
			(size 0.4572 0.4572)
			(layers "F.Cu" "F.Mask" "F.Paste")
			(net "P1V8_PEX")
		)
		(pad "Y13" smd circle
			(at -11.400028 -4.750054)
			(size 0.4572 0.4572)
			(layers "F.Cu" "F.Mask" "F.Paste")
			(net "GND")
		)
		(pad "Y14" smd circle
			(at -10.450068 -4.750054)
			(size 0.4572 0.4572)
			(layers "F.Cu" "F.Mask" "F.Paste")
			(net "P0V8_PEX1")
		)
		(pad "Y15" smd circle
			(at -9.500108 -4.750054)
			(size 0.4572 0.4572)
			(layers "F.Cu" "F.Mask" "F.Paste")
			(net "GND")
		)
		(pad "Y16" smd circle
			(at -8.549894 -4.750054)
			(size 0.4572 0.4572)
			(layers "F.Cu" "F.Mask" "F.Paste")
			(net "P0V8_SERDES_VDDA_PEX1")
		)
		(pad "Y17" smd circle
			(at -7.599934 -4.750054)
			(size 0.4572 0.4572)
			(layers "F.Cu" "F.Mask" "F.Paste")
			(net "P0V8_SERDES_VDDA_PEX1")
		)
		(pad "Y18" smd circle
			(at -6.649974 -4.750054)
			(size 0.4572 0.4572)
			(layers "F.Cu" "F.Mask" "F.Paste")
			(net "P0V8_SERDES_VDDA_PEX1")
		)
		(pad "Y19" smd circle
			(at -5.700014 -4.750054)
			(size 0.4572 0.4572)
			(layers "F.Cu" "F.Mask" "F.Paste")
			(net "P0V8_SERDES_VDDA_PEX1")
		)
		(pad "Y20" smd circle
			(at -4.750054 -4.750054)
			(size 0.4572 0.4572)
			(layers "F.Cu" "F.Mask" "F.Paste")
			(net "P0V8_SERDES_VDDA_PEX1")
		)
		(pad "Y21" smd circle
			(at -3.800094 -4.750054)
			(size 0.4572 0.4572)
			(layers "F.Cu" "F.Mask" "F.Paste")
			(net "P0V8_SERDES_VDDA_PEX1")
		)
		(pad "Y22" smd circle
			(at -2.84988 -4.750054)
			(size 0.4572 0.4572)
			(layers "F.Cu" "F.Mask" "F.Paste")
			(net "P0V8_SERDES_VDDA_PEX1")
		)
		(pad "Y23" smd circle
			(at -1.89992 -4.750054)
			(size 0.4572 0.4572)
			(layers "F.Cu" "F.Mask" "F.Paste")
			(net "P0V8_SERDES_VDDA_PEX1")
		)
		(pad "Y24" smd circle
			(at -0.94996 -4.750054)
			(size 0.4572 0.4572)
			(layers "F.Cu" "F.Mask" "F.Paste")
			(net "P0V8_SERDES_VDDA_PEX1")
		)
		(pad "Y25" smd circle
			(at 0 -4.750054)
			(size 0.4572 0.4572)
			(layers "F.Cu" "F.Mask" "F.Paste")
			(net "P0V8_SERDES_VDDA_PEX1")
		)
		(pad "Y26" smd circle
			(at 0.94996 -4.750054)
			(size 0.4572 0.4572)
			(layers "F.Cu" "F.Mask" "F.Paste")
			(net "P0V8_SERDES_VDDA_PEX1")
		)
		(pad "Y27" smd circle
			(at 1.89992 -4.750054)
			(size 0.4572 0.4572)
			(layers "F.Cu" "F.Mask" "F.Paste")
			(net "P0V8_SERDES_VDDA_PEX1")
		)
		(pad "Y28" smd circle
			(at 2.84988 -4.750054)
			(size 0.4572 0.4572)
			(layers "F.Cu" "F.Mask" "F.Paste")
			(net "P0V8_SERDES_VDDA_PEX1")
		)
		(pad "Y29" smd circle
			(at 3.800094 -4.750054)
			(size 0.4572 0.4572)
			(layers "F.Cu" "F.Mask" "F.Paste")
			(net "P0V8_SERDES_VDDA_PEX1")
		)
		(pad "Y30" smd circle
			(at 4.750054 -4.750054)
			(size 0.4572 0.4572)
			(layers "F.Cu" "F.Mask" "F.Paste")
			(net "P0V8_SERDES_VDDA_PEX1")
		)
		(pad "Y31" smd circle
			(at 5.700014 -4.750054)
			(size 0.4572 0.4572)
			(layers "F.Cu" "F.Mask" "F.Paste")
			(net "P0V8_SERDES_VDDA_PEX1")
		)
		(pad "Y32" smd circle
			(at 6.649974 -4.750054)
			(size 0.4572 0.4572)
			(layers "F.Cu" "F.Mask" "F.Paste")
			(net "P0V8_SERDES_VDDA_PEX1")
		)
		(pad "Y33" smd circle
			(at 7.599934 -4.750054)
			(size 0.4572 0.4572)
			(layers "F.Cu" "F.Mask" "F.Paste")
			(net "P0V8_SERDES_VDDA_PEX1")
		)
		(pad "Y34" smd circle
			(at 8.549894 -4.750054)
			(size 0.4572 0.4572)
			(layers "F.Cu" "F.Mask" "F.Paste")
			(net "GND")
		)
		(pad "Y35" smd circle
			(at 9.500108 -4.750054)
			(size 0.4572 0.4572)
			(layers "F.Cu" "F.Mask" "F.Paste")
			(net "P1V8_PEX")
		)
		(pad "Y36" smd circle
			(at 10.450068 -4.750054)
			(size 0.4572 0.4572)
			(layers "F.Cu" "F.Mask" "F.Paste")
			(net "GND")
		)
		(pad "Y37" smd circle
			(at 11.400028 -4.750054)
			(size 0.4572 0.4572)
			(layers "F.Cu" "F.Mask" "F.Paste")
			(net "GND")
		)
		(pad "Y38" smd circle
			(at 12.349988 -4.750054)
			(size 0.4572 0.4572)
			(layers "F.Cu" "F.Mask" "F.Paste")
			(net "GND")
		)
		(pad "Y39" smd circle
			(at 13.299948 -4.750054)
			(size 0.4572 0.4572)
			(layers "F.Cu" "F.Mask" "F.Paste")
			(net "PEX1_ADCTEMP_VINP0")
		)
		(pad "Y40" smd circle
			(at 14.249908 -4.750054)
			(size 0.4572 0.4572)
			(layers "F.Cu" "F.Mask" "F.Paste")
			(net "GND")
		)
		(pad "Y41" smd circle
			(at 15.200122 -4.750054)
			(size 0.4572 0.4572)
			(layers "F.Cu" "F.Mask" "F.Paste")
			(net "Net_1356")
		)
		(pad "Y42" smd circle
			(at 16.150082 -4.750054)
			(size 0.4572 0.4572)
			(layers "F.Cu" "F.Mask" "F.Paste")
			(net "Net_1410")
		)
		(pad "Y43" smd circle
			(at 17.100042 -4.750054)
			(size 0.4572 0.4572)
			(layers "F.Cu" "F.Mask" "F.Paste")
			(net "GND")
		)
		(pad "Y44" smd circle
			(at 18.050002 -4.750054)
			(size 0.4572 0.4572)
			(layers "F.Cu" "F.Mask" "F.Paste")
			(net "GND")
		)
		(pad "Y45" smd circle
			(at 18.999962 -4.750054)
			(size 0.4572 0.4572)
			(layers "F.Cu" "F.Mask" "F.Paste")
			(net "GND")
		)
		(pad "Y46" smd circle
			(at 19.949922 -4.750054)
			(size 0.4572 0.4572)
			(layers "F.Cu" "F.Mask" "F.Paste")
			(net "GND")
		)
		(pad "Y47" smd circle
			(at 20.899882 -4.750054)
			(size 0.4572 0.4572)
			(layers "F.Cu" "F.Mask" "F.Paste")
			(net "GND")
		)
		(pad "Y48" smd circle
			(at 21.850096 -4.750054)
			(size 0.4572 0.4572)
			(layers "F.Cu" "F.Mask" "F.Paste")
			(net "Net_1524")
		)
		(pad "Y49" smd circle
			(at 22.800056 -4.750054)
			(size 0.4572 0.4572)
			(layers "F.Cu" "F.Mask" "F.Paste")
			(net "Net_1546")
		)
	)
)
